(kicad_pcb
	(version 20241229)
	(generator "pcbnew")
	(generator_version "9.0")
	(general
		(thickness 1.292)
		(legacy_teardrops no)
	)
	(paper "A4")
	(title_block
		(title "LPDDR5 Testbed")
		(date "2023-12-19")
		(rev "1.0.0")
		(comment 9 "footprints 96-101 of 160")
	)
	(layers
		(0 "F.Cu" signal)
		(4 "In1.Cu" power)
		(6 "In2.Cu" power)
		(8 "In3.Cu" signal)
		(10 "In4.Cu" signal)
		(2 "B.Cu" signal)
		(9 "F.Adhes" user "F.Adhesive")
		(11 "B.Adhes" user "B.Adhesive")
		(13 "F.Paste" user)
		(15 "B.Paste" user)
		(5 "F.SilkS" user "F.Silkscreen")
		(7 "B.SilkS" user "B.Silkscreen")
		(1 "F.Mask" user)
		(3 "B.Mask" user)
		(17 "Dwgs.User" user "User.Drawings")
		(19 "Cmts.User" user "User.Comments")
		(21 "Eco1.User" user "User.Eco1")
		(23 "Eco2.User" user "User.Eco2")
		(25 "Edge.Cuts" user)
		(27 "Margin" user)
		(31 "F.CrtYd" user "F.Courtyard")
		(29 "B.CrtYd" user "B.Courtyard")
		(35 "F.Fab" user)
		(33 "B.Fab" user)
	)
	(footprint "antmicro-footprints:R_Array_4x0402_Panasonic_EXB28V"
		(layer "B.Cu")
		(at 155.7 93.85)
		(property "Reference" "R78"
			(at -1.1 1.8 0)
			(unlocked yes)
			(layer "B.SilkS")
			(effects
				(font
					(size 0.7 0.7)
					(thickness 0.15)
				)
				(justify right bottom mirror)
			)
		)
		(property "Value" "R_4x100R_0402_array"
			(at -1.5 -2 0)
			(layer "B.Fab")
			(effects
				(font
					(size 0.7 0.7)
					(thickness 0.15)
				)
				(justify right bottom mirror)
			)
		)
		(property "Author" "Antmicro"
			(at 0 0 0)
			(layer "B.Fab")
			(hide yes)
			(effects
				(font
					(size 1 1)
					(thickness 0.15)
				)
				(justify mirror)
			)
		)
		(property "License" "Apache-2.0"
			(at 0 0 0)
			(layer "B.Fab")
			(hide yes)
			(effects
				(font
					(size 1 1)
					(thickness 0.15)
				)
				(justify mirror)
			)
		)
		(property "MPN" "EXB-28V101JX"
			(at 0 0 0)
			(layer "B.Fab")
			(hide yes)
			(effects
				(font
					(size 1 1)
					(thickness 0.15)
				)
				(justify mirror)
			)
		)
		(property "Manufacturer" "Panasonic"
			(at 0 0 0)
			(layer "B.Fab")
			(hide yes)
			(effects
				(font
					(size 1 1)
					(thickness 0.15)
				)
				(justify mirror)
			)
		)
		(property "Val" "R_4x100R_0402"
			(at 0 0 0)
			(layer "B.Fab")
			(hide yes)
			(effects
				(font
					(size 1 1)
					(thickness 0.15)
				)
				(justify mirror)
			)
		)
		(sheetname "Translators1")
		(sheetfile "translators.kicad_sch")
		(attr smd)
		(fp_line
			(start -1.25 0.5)
			(end -1.25 -0.498)
			(stroke
				(width 0.15)
				(type solid)
			)
			(layer "B.SilkS")
		)
		(fp_line
			(start 1.25 -0.499)
			(end 1.25 0.499)
			(stroke
				(width 0.15)
				(type solid)
			)
			(layer "B.SilkS")
		)
		(fp_rect
			(start -1.25 0.8)
			(end 1.25 -0.8)
			(stroke
				(width 0.05)
				(type solid)
			)
			(fill no)
			(layer "B.CrtYd")
		)
		(fp_line
			(start -1 -0.498)
			(end -1 0.5)
			(stroke
				(width 0.15)
				(type solid)
			)
			(layer "B.Fab")
		)
		(fp_line
			(start -1 0.5)
			(end 0.998 0.5)
			(stroke
				(width 0.15)
				(type solid)
			)
			(layer "B.Fab")
		)
		(fp_line
			(start 0.998 -0.498)
			(end -1 -0.498)
			(stroke
				(width 0.15)
				(type solid)
			)
			(layer "B.Fab")
		)
		(fp_line
			(start 0.998 0.5)
			(end 0.998 -0.498)
			(stroke
				(width 0.15)
				(type solid)
			)
			(layer "B.Fab")
		)
		(pad "1" smd roundrect
			(at -0.8875 -0.45)
			(size 0.525 0.5)
			(layers "B.Cu" "B.Mask" "B.Paste")
			(roundrect_rratio 0.25)
			(net 216 "/LPDDR5/LPDDR5_B.DQ15")
			(pinfunction "R1.1")
			(pintype "passive")
		)
		(pad "2" smd roundrect
			(at -0.25 -0.45)
			(size 0.25 0.5)
			(layers "B.Cu" "B.Mask" "B.Paste")
			(roundrect_rratio 0.25)
			(net 215 "/LPDDR5/LPDDR5_B.DQ14")
			(pinfunction "R2.1")
			(pintype "passive")
		)
		(pad "3" smd roundrect
			(at 0.25 -0.45)
			(size 0.25 0.5)
			(layers "B.Cu" "B.Mask" "B.Paste")
			(roundrect_rratio 0.25)
			(net 213 "/LPDDR5/LPDDR5_B.DQ12")
			(pinfunction "R3.1")
			(pintype "passive")
		)
		(pad "4" smd roundrect
			(at 0.8875 -0.45)
			(size 0.525 0.5)
			(layers "B.Cu" "B.Mask" "B.Paste")
			(roundrect_rratio 0.25)
			(net 214 "/LPDDR5/LPDDR5_B.DQ13")
			(pinfunction "R4.1")
			(pintype "passive")
		)
		(pad "5" smd roundrect
			(at 0.8875 0.45)
			(size 0.525 0.5)
			(layers "B.Cu" "B.Mask" "B.Paste")
			(roundrect_rratio 0.25)
			(net 14 "GND")
			(pinfunction "R4.2")
			(pintype "passive")
		)
		(pad "6" smd roundrect
			(at 0.25 0.45)
			(size 0.25 0.5)
			(layers "B.Cu" "B.Mask" "B.Paste")
			(roundrect_rratio 0.25)
			(net 14 "GND")
			(pinfunction "R3.2")
			(pintype "passive")
		)
		(pad "7" smd roundrect
			(at -0.25 0.45)
			(size 0.25 0.5)
			(layers "B.Cu" "B.Mask" "B.Paste")
			(roundrect_rratio 0.25)
			(net 14 "GND")
			(pinfunction "R2.2")
			(pintype "passive")
		)
		(pad "8" smd roundrect
			(at -0.8875 0.45)
			(size 0.525 0.5)
			(layers "B.Cu" "B.Mask" "B.Paste")
			(roundrect_rratio 0.25)
			(net 14 "GND")
			(pinfunction "R1.2")
			(pintype "passive")
		)
	)
	(footprint "antmicro-footprints:C_0402_1005Metric"
		(layer "B.Cu")
		(at 129.175 84.95 180)
		(descr "Capacitor SMD 0402")
		(tags "capacitor SMD 0402")
		(property "Reference" "C39"
			(at 0.875 -0.35 0)
			(unlocked yes)
			(layer "B.SilkS")
			(effects
				(font
					(size 0.7 0.7)
					(thickness 0.15)
				)
				(justify left bottom mirror)
			)
		)
		(property "Value" "C_4u7_0402"
			(at -1.022927 -2.155213 0)
			(layer "B.Fab")
			(effects
				(font
					(size 0.7 0.7)
					(thickness 0.15)
				)
				(justify left bottom mirror)
			)
		)
		(property "Author" "Antmicro"
			(at 258.35 169.9 0)
			(layer "B.Fab")
			(hide yes)
			(effects
				(font
					(size 1 1)
					(thickness 0.15)
				)
				(justify mirror)
			)
		)
		(property "Dielectric" ""
			(at 258.35 169.9 0)
			(layer "B.Fab")
			(hide yes)
			(effects
				(font
					(size 1 1)
					(thickness 0.15)
				)
				(justify mirror)
			)
		)
		(property "License" "Apache-2.0"
			(at 258.35 169.9 0)
			(layer "B.Fab")
			(hide yes)
			(effects
				(font
					(size 1 1)
					(thickness 0.15)
				)
				(justify mirror)
			)
		)
		(property "MPN" "GRM155R61A475MEAAD"
			(at 258.35 169.9 0)
			(layer "B.Fab")
			(hide yes)
			(effects
				(font
					(size 1 1)
					(thickness 0.15)
				)
				(justify mirror)
			)
		)
		(property "Manufacturer" "Murata"
			(at 258.35 169.9 0)
			(layer "B.Fab")
			(hide yes)
			(effects
				(font
					(size 1 1)
					(thickness 0.15)
				)
				(justify mirror)
			)
		)
		(property "Val" "4u7"
			(at 258.35 169.9 0)
			(layer "B.Fab")
			(hide yes)
			(effects
				(font
					(size 1 1)
					(thickness 0.15)
				)
				(justify mirror)
			)
		)
		(property "Voltage" ""
			(at 258.35 169.9 0)
			(layer "B.Fab")
			(hide yes)
			(effects
				(font
					(size 1 1)
					(thickness 0.15)
				)
				(justify mirror)
			)
		)
		(sheetname "LPDDR5")
		(sheetfile "lpddr5.kicad_sch")
		(attr smd)
		(fp_rect
			(start -0.9659 0.481258)
			(end 0.9649 -0.458742)
			(stroke
				(width 0.05)
				(type solid)
			)
			(fill no)
			(layer "B.CrtYd")
		)
		(fp_line
			(start 0.499 0.25)
			(end 0.499 -0.248)
			(stroke
				(width 0.15)
				(type solid)
			)
			(layer "B.Fab")
		)
		(fp_line
			(start 0.499 -0.248)
			(end -0.499 -0.248)
			(stroke
				(width 0.15)
				(type solid)
			)
			(layer "B.Fab")
		)
		(fp_line
			(start -0.499 0.25)
			(end 0.499 0.25)
			(stroke
				(width 0.15)
				(type solid)
			)
			(layer "B.Fab")
		)
		(fp_line
			(start -0.499 -0.248)
			(end -0.499 0.25)
			(stroke
				(width 0.15)
				(type solid)
			)
			(layer "B.Fab")
		)
		(pad "1" smd roundrect
			(at -0.484 0 180)
			(size 0.59 0.64)
			(layers "B.Cu" "B.Mask" "B.Paste")
			(roundrect_rratio 0.25)
			(net 14 "GND")
			(pintype "passive")
		)
		(pad "2" smd roundrect
			(at 0.484 0 180)
			(size 0.59 0.64)
			(layers "B.Cu" "B.Mask" "B.Paste")
			(roundrect_rratio 0.25)
			(net 4 "+0V5")
			(pintype "passive")
		)
	)
	(footprint "antmicro-footprints:R_0402_1005Metric"
		(layer "B.Cu")
		(at 118.58 89.5)
		(descr "Resistor SMD 0402")
		(tags "resistor SMD 0402")
		(property "Reference" "R48"
			(at -0.98 -0.6 0)
			(unlocked yes)
			(layer "B.SilkS")
			(effects
				(font
					(size 0.7 0.7)
					(thickness 0.15)
				)
				(justify right bottom mirror)
			)
		)
		(property "Value" "R_100R_0402"
			(at -1.011843 -1.772047 0)
			(layer "B.Fab")
			(effects
				(font
					(size 0.7 0.7)
					(thickness 0.15)
				)
				(justify right bottom mirror)
			)
		)
		(property "Author" "Antmicro"
			(at 0 0 0)
			(layer "B.Fab")
			(hide yes)
			(effects
				(font
					(size 1 1)
					(thickness 0.15)
				)
				(justify mirror)
			)
		)
		(property "License" "Apache-2.0"
			(at 0 0 0)
			(layer "B.Fab")
			(hide yes)
			(effects
				(font
					(size 1 1)
					(thickness 0.15)
				)
				(justify mirror)
			)
		)
		(property "MPN" "CR0402-FX-1000GLF"
			(at 0 0 0)
			(layer "B.Fab")
			(hide yes)
			(effects
				(font
					(size 1 1)
					(thickness 0.15)
				)
				(justify mirror)
			)
		)
		(property "Manufacturer" "Bourns"
			(at 0 0 0)
			(layer "B.Fab")
			(hide yes)
			(effects
				(font
					(size 1 1)
					(thickness 0.15)
				)
				(justify mirror)
			)
		)
		(property "Tolerance" "1%"
			(at 0 0 0)
			(layer "B.Fab")
			(hide yes)
			(effects
				(font
					(size 1 1)
					(thickness 0.15)
				)
				(justify mirror)
			)
		)
		(property "Val" "100R"
			(at 0 0 0)
			(layer "B.Fab")
			(hide yes)
			(effects
				(font
					(size 1 1)
					(thickness 0.15)
				)
				(justify mirror)
			)
		)
		(sheetname "Translators")
		(sheetfile "translators.kicad_sch")
		(attr smd)
		(fp_rect
			(start -0.93 0.47)
			(end 0.93 -0.47)
			(stroke
				(width 0.05)
				(type solid)
			)
			(fill no)
			(layer "B.CrtYd")
		)
		(fp_rect
			(start -0.5 0.25)
			(end 0.5 -0.25)
			(stroke
				(width 0.15)
				(type solid)
			)
			(fill no)
			(layer "B.Fab")
		)
		(pad "1" smd roundrect
			(at -0.485 0)
			(size 0.59 0.64)
			(layers "B.Cu" "B.Mask" "B.Paste")
			(roundrect_rratio 0.25)
			(net 45 "/LPDDR5/LPDDR5_A.WCK0_P")
			(pintype "passive")
		)
		(pad "2" smd roundrect
			(at 0.485 0)
			(size 0.59 0.64)
			(layers "B.Cu" "B.Mask" "B.Paste")
			(roundrect_rratio 0.25)
			(net 14 "GND")
			(pintype "passive")
		)
	)
	(footprint "antmicro-footprints:R_0402_1005Metric"
		(layer "B.Cu")
		(at 132.1 93.8 -90)
		(descr "Resistor SMD 0402")
		(tags "resistor SMD 0402")
		(property "Reference" "R86"
			(at 0.8 -0.4 90)
			(unlocked yes)
			(layer "B.SilkS")
			(effects
				(font
					(size 0.7 0.7)
					(thickness 0.15)
				)
				(justify left bottom mirror)
			)
		)
		(property "Value" "R_100R_0402"
			(at -1.011843 -1.772047 90)
			(layer "B.Fab")
			(effects
				(font
					(size 0.7 0.7)
					(thickness 0.15)
				)
				(justify left bottom mirror)
			)
		)
		(property "Author" "Antmicro"
			(at 38.3 225.9 0)
			(layer "B.Fab")
			(hide yes)
			(effects
				(font
					(size 1 1)
					(thickness 0.15)
				)
				(justify mirror)
			)
		)
		(property "License" "Apache-2.0"
			(at 38.3 225.9 0)
			(layer "B.Fab")
			(hide yes)
			(effects
				(font
					(size 1 1)
					(thickness 0.15)
				)
				(justify mirror)
			)
		)
		(property "MPN" "CR0402-FX-1000GLF"
			(at 38.3 225.9 0)
			(layer "B.Fab")
			(hide yes)
			(effects
				(font
					(size 1 1)
					(thickness 0.15)
				)
				(justify mirror)
			)
		)
		(property "Manufacturer" "Bourns"
			(at 38.3 225.9 0)
			(layer "B.Fab")
			(hide yes)
			(effects
				(font
					(size 1 1)
					(thickness 0.15)
				)
				(justify mirror)
			)
		)
		(property "Tolerance" "1%"
			(at 38.3 225.9 0)
			(layer "B.Fab")
			(hide yes)
			(effects
				(font
					(size 1 1)
					(thickness 0.15)
				)
				(justify mirror)
			)
		)
		(property "Val" "100R"
			(at 38.3 225.9 0)
			(layer "B.Fab")
			(hide yes)
			(effects
				(font
					(size 1 1)
					(thickness 0.15)
				)
				(justify mirror)
			)
		)
		(sheetname "Translators")
		(sheetfile "translators.kicad_sch")
		(attr smd)
		(fp_rect
			(start -0.93 0.47)
			(end 0.93 -0.47)
			(stroke
				(width 0.05)
				(type solid)
			)
			(fill no)
			(layer "B.CrtYd")
		)
		(fp_rect
			(start -0.5 0.25)
			(end 0.5 -0.25)
			(stroke
				(width 0.15)
				(type solid)
			)
			(fill no)
			(layer "B.Fab")
		)
		(pad "1" smd roundrect
			(at -0.485 0 270)
			(size 0.59 0.64)
			(layers "B.Cu" "B.Mask" "B.Paste")
			(roundrect_rratio 0.25)
			(net 55 "/LPDDR5/LPDDR5_A.CA6")
			(pintype "passive")
		)
		(pad "2" smd roundrect
			(at 0.485 0 270)
			(size 0.59 0.64)
			(layers "B.Cu" "B.Mask" "B.Paste")
			(roundrect_rratio 0.25)
			(net 14 "GND")
			(pintype "passive")
		)
	)
	(footprint "antmicro-footprints:R_0402_1005Metric"
		(layer "B.Cu")
		(at 137.65 93.85 -90)
		(descr "Resistor SMD 0402")
		(tags "resistor SMD 0402")
		(property "Reference" "R83"
			(at 0.85 -0.35 90)
			(unlocked yes)
			(layer "B.SilkS")
			(effects
				(font
					(size 0.7 0.7)
					(thickness 0.15)
				)
				(justify left bottom mirror)
			)
		)
		(property "Value" "R_100R_0402"
			(at -1.011843 -1.772047 90)
			(layer "B.Fab")
			(effects
				(font
					(size 0.7 0.7)
					(thickness 0.15)
				)
				(justify left bottom mirror)
			)
		)
		(property "Author" "Antmicro"
			(at 43.8 231.5 0)
			(layer "B.Fab")
			(hide yes)
			(effects
				(font
					(size 1 1)
					(thickness 0.15)
				)
				(justify mirror)
			)
		)
		(property "License" "Apache-2.0"
			(at 43.8 231.5 0)
			(layer "B.Fab")
			(hide yes)
			(effects
				(font
					(size 1 1)
					(thickness 0.15)
				)
				(justify mirror)
			)
		)
		(property "MPN" "CR0402-FX-1000GLF"
			(at 43.8 231.5 0)
			(layer "B.Fab")
			(hide yes)
			(effects
				(font
					(size 1 1)
					(thickness 0.15)
				)
				(justify mirror)
			)
		)
		(property "Manufacturer" "Bourns"
			(at 43.8 231.5 0)
			(layer "B.Fab")
			(hide yes)
			(effects
				(font
					(size 1 1)
					(thickness 0.15)
				)
				(justify mirror)
			)
		)
		(property "Tolerance" "1%"
			(at 43.8 231.5 0)
			(layer "B.Fab")
			(hide yes)
			(effects
				(font
					(size 1 1)
					(thickness 0.15)
				)
				(justify mirror)
			)
		)
		(property "Val" "100R"
			(at 43.8 231.5 0)
			(layer "B.Fab")
			(hide yes)
			(effects
				(font
					(size 1 1)
					(thickness 0.15)
				)
				(justify mirror)
			)
		)
		(sheetname "Translators1")
		(sheetfile "translators.kicad_sch")
		(attr smd)
		(fp_rect
			(start -0.93 0.47)
			(end 0.93 -0.47)
			(stroke
				(width 0.05)
				(type solid)
			)
			(fill no)
			(layer "B.CrtYd")
		)
		(fp_rect
			(start -0.5 0.25)
			(end 0.5 -0.25)
			(stroke
				(width 0.15)
				(type solid)
			)
			(fill no)
			(layer "B.Fab")
		)
		(pad "1" smd roundrect
			(at -0.485 0 270)
			(size 0.59 0.64)
			(layers "B.Cu" "B.Mask" "B.Paste")
			(roundrect_rratio 0.25)
			(net 113 "/LPDDR5/LPDDR5_B.CK_N")
			(pintype "passive")
		)
		(pad "2" smd roundrect
			(at 0.485 0 270)
			(size 0.59 0.64)
			(layers "B.Cu" "B.Mask" "B.Paste")
			(roundrect_rratio 0.25)
			(net 14 "GND")
			(pintype "passive")
		)
	)
	(footprint "antmicro-footprints:R_0402_1005Metric"
		(layer "B.Cu")
		(at 108.25 79.7 90)
		(descr "Resistor SMD 0402")
		(tags "resistor SMD 0402")
		(property "Reference" "R27"
			(at -1 -0.55 90)
			(unlocked yes)
			(layer "B.SilkS")
			(effects
				(font
					(size 0.7 0.7)
					(thickness 0.15)
				)
				(justify right bottom mirror)
			)
		)
		(property "Value" "R_0R_0402"
			(at -1.011843 -1.772047 90)
			(layer "B.Fab")
			(effects
				(font
					(size 0.7 0.7)
					(thickness 0.15)
				)
				(justify right bottom mirror)
			)
		)
		(property "Author" "Antmicro"
			(at 187.95 -28.55 0)
			(layer "B.Fab")
			(hide yes)
			(effects
				(font
					(size 1 1)
					(thickness 0.15)
				)
				(justify mirror)
			)
		)
		(property "Current" "1A"
			(at 187.95 -28.55 0)
			(layer "B.Fab")
			(hide yes)
			(effects
				(font
					(size 1 1)
					(thickness 0.15)
				)
				(justify mirror)
			)
		)
		(property "License" "Apache-2.0"
			(at 187.95 -28.55 0)
			(layer "B.Fab")
			(hide yes)
			(effects
				(font
					(size 1 1)
					(thickness 0.15)
				)
				(justify mirror)
			)
		)
		(property "MPN" "ERJ2GE0R00X"
			(at 187.95 -28.55 0)
			(layer "B.Fab")
			(hide yes)
			(effects
				(font
					(size 1 1)
					(thickness 0.15)
				)
				(justify mirror)
			)
		)
		(property "Manufacturer" "Panasonic"
			(at 187.95 -28.55 0)
			(layer "B.Fab")
			(hide yes)
			(effects
				(font
					(size 1 1)
					(thickness 0.15)
				)
				(justify mirror)
			)
		)
		(property "Tolerance" ""
			(at 187.95 -28.55 0)
			(layer "B.Fab")
			(hide yes)
			(effects
				(font
					(size 1 1)
					(thickness 0.15)
				)
				(justify mirror)
			)
		)
		(property "Val" "0R"
			(at 187.95 -28.55 0)
			(layer "B.Fab")
			(hide yes)
			(effects
				(font
					(size 1 1)
					(thickness 0.15)
				)
				(justify mirror)
			)
		)
		(sheetname "SODIMM")
		(sheetfile "sodim.kicad_sch")
		(attr smd)
		(fp_rect
			(start -0.93 0.47)
			(end 0.93 -0.47)
			(stroke
				(width 0.05)
				(type solid)
			)
			(fill no)
			(layer "B.CrtYd")
		)
		(fp_rect
			(start -0.5 0.25)
			(end 0.5 -0.25)
			(stroke
				(width 0.15)
				(type solid)
			)
			(fill no)
			(layer "B.Fab")
		)
		(pad "1" smd roundrect
			(at -0.485 0 90)
			(size 0.59 0.64)
			(layers "B.Cu" "B.Mask" "B.Paste")
			(roundrect_rratio 0.25)
			(net 19 "/SODIMM/HSDA")
			(pintype "passive")
		)
		(pad "2" smd roundrect
			(at 0.485 0 90)
			(size 0.59 0.64)
			(layers "B.Cu" "B.Mask" "B.Paste")
			(roundrect_rratio 0.25)
			(net 38 "/Power supply/I2C.SDA")
			(pintype "passive")
		)
	)
)
